#ISCELL
  mstr_misc dns *
  *
#ISCELL
  pure_quanta quanta_title_block_c *
  *
#ISCELL
  pure_quanta_power cad_note *
  *
#CELL
  pure_quanta sn74avc2t245rswr *
  page149_i1
#CELL
  pure_quanta q_cap *
  page149_i10
#CELL
  pure_quanta q_res *
  page149_i101
#CELL
  pure_quanta mosfet_n *
  page149_i102
#CELL
  pure_quanta q_res *
  page149_i109
#ISCELL
  pure_quanta_power gnd *
  page149_i11
#ISCELL
  pure_quanta_power gnd *
  page149_i110
#CELL
  pure_quanta q_res *
  page149_i111
#CELL
  pure_quanta q_res *
  page149_i112
#CELL
  pure_quanta q_res *
  page149_i113
#CELL
  pure_quanta q_res *
  page149_i114
#CELL
  pure_quanta q_res *
  page149_i115
#CELL
  pure_quanta q_res *
  page149_i116
#CELL
  pure_quanta q_res *
  page149_i117
#CELL
  pure_quanta q_res *
  page149_i118
#ISCELL
  pure_quanta_power universal_power *
  page149_i119
#ISCELL
  pure_quanta_power universal_power *
  page149_i12
#ISCELL
  pure_quanta_power gnd *
  page149_i120
#ISCELL
  pure_quanta_power gnd *
  page149_i121
#CELL
  pure_quanta q_cap *
  page149_i123
#ISCELL
  standard offpage *
  page149_i124
#ISCELL
  standard offpage *
  page149_i125
#ISCELL
  standard offpage *
  page149_i126
#ISCELL
  standard offpage *
  page149_i127
#ISCELL
  standard offpage *
  page149_i128
#ISCELL
  standard offpage *
  page149_i129
#ISCELL
  standard offpage *
  page149_i130
#ISCELL
  standard offpage *
  page149_i131
#CELL
  pure_quanta q_res *
  page149_i132
#CELL
  pure_quanta q_res *
  page149_i133
#CELL
  pure_quanta q_cap *
  page149_i134
#CELL
  pure_quanta q_cap *
  page149_i137
#ISCELL
  pure_quanta_power gnd *
  page149_i138
#CELL
  pure_quanta q_cap *
  page149_i140
#ISCELL
  pure_quanta_power gnd *
  page149_i141
#CELL
  pure_quanta sconn20_hsu2101l00007h *
  page149_i142
#ISCELL
  pure_quanta_power gnd *
  page149_i143
#ISCELL
  pure_quanta_power universal_power *
  page149_i144
#ISCELL
  pure_quanta_power universal_power *
  page149_i145
#CELL
  pure_quanta q_res *
  page149_i146
#CELL
  pure_quanta q_res *
  page149_i147
#CELL
  pure_quanta q_res *
  page149_i148
#CELL
  pure_quanta q_res *
  page149_i149
#CELL
  pure_quanta q_res *
  page149_i150
#ISCELL
  pure_quanta_power gnd *
  page149_i151
#CELL
  pure_quanta q_cap *
  page149_i152
#ISCELL
  standard offpage *
  page149_i153
#ISCELL
  standard offpage *
  page149_i154
#ISCELL
  standard offpage *
  page149_i155
#ISCELL
  standard offpage *
  page149_i156
#CELL
  pure_quanta q_res *
  page149_i157
#ISCELL
  standard offpage *
  page149_i158
#ISCELL
  pure_quanta_power universal_power *
  page149_i20
#CELL
  pure_quanta q_cap *
  page149_i21
#ISCELL
  pure_quanta_power gnd *
  page149_i22
#CELL
  pure_quanta q_cap *
  page149_i23
#ISCELL
  pure_quanta_power gnd *
  page149_i24
#CELL
  pure_quanta q_cap *
  page149_i25
#ISCELL
  pure_quanta_power gnd *
  page149_i26
#ISCELL
  pure_quanta_power gnd *
  page149_i27
#ISCELL
  pure_quanta_power universal_power *
  page149_i28
#CELL
  pure_quanta q_cap *
  page149_i29
#ISCELL
  standard offpage *
  page149_i3
#ISCELL
  pure_quanta_power gnd *
  page149_i30
#CELL
  pure_quanta sn74avc4t774pwr *
  page149_i31
#ISCELL
  pure_quanta_power universal_power *
  page149_i32
#ISCELL
  pure_quanta_power gnd *
  page149_i33
#CELL
  pure_quanta sn74avc4t774pwr *
  page149_i34
#ISCELL
  standard offpage *
  page149_i4
#CELL
  pure_quanta q_cap *
  page149_i41
#ISCELL
  pure_quanta_power gnd *
  page149_i42
#ISCELL
  standard offpage *
  page149_i43
#ISCELL
  standard offpage *
  page149_i44
#ISCELL
  standard offpage *
  page149_i45
#ISCELL
  standard offpage *
  page149_i46
#ISCELL
  standard offpage *
  page149_i5
#ISCELL
  standard offpage *
  page149_i51
#CELL
  pure_quanta q_res *
  page149_i53
#ISCELL
  pure_quanta_power universal_power *
  page149_i54
#ISCELL
  pure_quanta_power gnd *
  page149_i55
#CELL
  pure_quanta q_cap *
  page149_i56
#ISCELL
  standard offpage *
  page149_i6
#CELL
  pure_quanta q_cap *
  page149_i62
#ISCELL
  pure_quanta_power gnd *
  page149_i63
#ISCELL
  standard offpage *
  page149_i64
#ISCELL
  standard offpage *
  page149_i65
#CELL
  pure_quanta q_cap *
  page149_i66
#ISCELL
  pure_quanta_power gnd *
  page149_i67
#ISCELL
  standard offpage *
  page149_i68
#ISCELL
  standard offpage *
  page149_i69
#CELL
  pure_quanta q_res *
  page149_i7
#ISCELL
  standard offpage *
  page149_i70
#ISCELL
  pure_quanta_power universal_power *
  page149_i71
#ISCELL
  pure_quanta_power universal_power *
  page149_i73
#CELL
  pure_quanta q_cap *
  page149_i74
#ISCELL
  pure_quanta_power gnd *
  page149_i75
#CELL
  pure_quanta sn74avc2t245rswr *
  page149_i76
#ISCELL
  pure_quanta_power gnd *
  page149_i77
#ISCELL
  pure_quanta_power universal_power *
  page149_i78
#CELL
  pure_quanta q_res *
  page149_i8
#CELL
  pure_quanta q_cap *
  page149_i80
#ISCELL
  pure_quanta_power gnd *
  page149_i81
#ISCELL
  pure_quanta_power universal_power *
  page149_i82
#CELL
  pure_quanta q_res *
  page149_i83
#ISCELL
  pure_quanta_power gnd *
  page149_i84
#ISCELL
  pure_quanta_power gnd *
  page149_i85
#CELL
  pure_quanta q_res *
  page149_i9
#ISCELL
  standard offpage *
  page149_i90
#ISCELL
  standard offpage *
  page149_i91
#CELL
  pure_quanta q_res *
  page149_i92
#ISCELL
  standard offpage *
  page149_i93
#ISCELL
  standard offpage *
  page149_i94
#ISCELL
  standard offpage *
  page149_i95
#CELL
  pure_quanta q_res *
  page149_i96
